Created on vSure / Trilogy - Netlist Compare Summary.

Version 

FTP Site : valor.com
WEB Site : http://www.valor.com 

DATE :  01 Aug 2014
TIME :  18:10:31


     MISMATCH SUMMARY REPORT
     -----------------------

Job  : 14545-sa_z10070163      Job  : 14545-sa_z10070163
Step : db                      Step : db
Type : CAD                     Type : CURCAD

-----------------------------------------------

 Mismatch Type: shorted

   GND                   -   NET00000            
   P5VC_AGND             -    "                  
   P5VB_AGND             -    "                  
   P5VA_AGND             -    "                  
   P12V                  -   NET00002            
   P3V3_IN               -    "                  
   P3V3                  -   NET00022            
   P3V3_LX_COOPER        -    "                  

 Total : 3
-----------------------------------------------

 Mismatch Type: broken


 Total : 0
-----------------------------------------------

 Mismatch Type: missing


 Total : 0
-----------------------------------------------

 Mismatch Type: extra


 Total : 0
-----------------------------------------------
